(kicad_pcb
	(version 20260206)
	(generator "pcbnew")
	(generator_version "10.0")
	(general
		(thickness 1.6)
		(legacy_teardrops no)
	)
	(paper "A4")
	(title_block
		(title "Bryce Canyon_SCC_16316-1_OCP.brd")
		(comment 1 "Bryce Canyon / footprints 936-943 of 1561")
	)
	(layers
		(0 "F.Cu" signal "TOP")
		(4 "In1.Cu" signal "L2GND")
		(6 "In2.Cu" signal "L3")
		(8 "In3.Cu" signal "L4VCC")
		(10 "In4.Cu" signal "L5VCC")
		(12 "In5.Cu" signal "L6")
		(14 "In6.Cu" signal "L7GND")
		(2 "B.Cu" signal "BOTTOM")
		(9 "F.Adhes" user "F.Adhesive")
		(11 "B.Adhes" user "B.Adhesive")
		(13 "F.Paste" user "Package Geometry/Pastemask Top")
		(15 "B.Paste" user "Package Geometry/Pastemask Bottom")
		(5 "F.SilkS" user "Ref Des/Silkscreen Top")
		(7 "B.SilkS" user "Ref Des/Silkscreen Bottom")
		(1 "F.Mask" user "Board Geometry/Soldermask Top")
		(3 "B.Mask" user "Board Geometry/Soldermask Bottom")
		(17 "Dwgs.User" user "User.Drawings")
		(19 "Cmts.User" user "User.Comments")
		(21 "Eco1.User" user "User.Eco1")
		(23 "Eco2.User" user "User.Eco2")
		(25 "Edge.Cuts" user "Board Geometry/Outline")
		(27 "Margin" user)
		(31 "F.CrtYd" user "Package Geometry/Place Bound Top")
		(29 "B.CrtYd" user "Package Geometry/Place Bound Bottom")
		(35 "F.Fab" user "Ref Des/Assembly Top")
		(33 "B.Fab" user "Ref Des/Assembly Bottom")
	)
	(footprint ""
		(layer "B.Cu")
		(at 76.327 -46.609)
		(property "Reference" "C303"
			(at 0 0 0)
			(layer "B.SilkS")
			(hide yes)
			(effects
				(font
					(size 1.27 1.27)
				)
				(justify mirror)
			)
		)
		(property "Value" "SC22U6D3V3MX-9-GP-U"
			(at 0 -2.8194 0)
			(unlocked yes)
			(layer "B.Fab")
			(hide yes)
			(effects
				(font
					(size 1.016 1.016)
					(thickness 0.1524)
				)
				(justify mirror)
			)
		)
		(property "Device Type" "C603H40"
			(at 0 -4.3434 0)
			(unlocked yes)
			(layer "B.Fab")
			(hide yes)
			(effects
				(font
					(size 1.016 1.016)
					(thickness 0.1524)
				)
				(justify mirror)
			)
		)
		(duplicate_pad_numbers_are_jumpers no)
		(fp_line
			(start -0.508 0)
			(end 0.508 0)
			(stroke
				(width 0.2032)
				(type default)
			)
			(layer "B.SilkS")
		)
		(fp_rect
			(start 0.5842 1.3335)
			(end -0.5842 -1.3335)
			(stroke
				(width 0)
				(type default)
			)
			(fill no)
			(layer "B.CrtYd")
		)
		(fp_rect
			(start 0.5842 1.3335)
			(end -0.5842 -1.3335)
			(stroke
				(width 0)
				(type default)
			)
			(fill no)
			(layer "B.Fab")
		)
		(pad "1" smd custom
			(at 0 -0.762 180)
			(size 0.2159 0.2159)
			(layers "B.Cu" "B.Mask" "B.Paste")
			(net "GB_VDDA")
			(options
				(clearance outline)
				(anchor circle)
			)
			(primitives
				(gr_poly
					(pts
						(arc
							(start -0.3302 0.4318)
							(mid -0.402042 0.402042)
							(end -0.4318 0.3302)
						)
						(arc
							(start -0.4318 -0.3302)
							(mid -0.402042 -0.402042)
							(end -0.3302 -0.4318)
						)
						(arc
							(start 0.3302 -0.4318)
							(mid 0.402042 -0.402042)
							(end 0.4318 -0.3302)
						)
						(arc
							(start 0.4318 0.3302)
							(mid 0.402042 0.402042)
							(end 0.3302 0.4318)
						)
					)
					(width 0)
					(fill yes)
				)
			)
		)
		(pad "2" smd custom
			(at 0 0.762 180)
			(size 0.2159 0.2159)
			(layers "B.Cu" "B.Mask" "B.Paste")
			(net "GND")
			(options
				(clearance outline)
				(anchor circle)
			)
			(primitives
				(gr_poly
					(pts
						(arc
							(start -0.3302 0.4318)
							(mid -0.402042 0.402042)
							(end -0.4318 0.3302)
						)
						(arc
							(start -0.4318 -0.3302)
							(mid -0.402042 -0.402042)
							(end -0.3302 -0.4318)
						)
						(arc
							(start 0.3302 -0.4318)
							(mid 0.402042 -0.402042)
							(end 0.4318 -0.3302)
						)
						(arc
							(start 0.4318 0.3302)
							(mid 0.402042 0.402042)
							(end 0.3302 0.4318)
						)
					)
					(width 0)
					(fill yes)
				)
			)
		)
	)
	(footprint ""
		(layer "B.Cu")
		(at 115.4938 -70.3834 180)
		(property "Reference" "C176"
			(at 0 0 0)
			(layer "B.SilkS")
			(hide yes)
			(effects
				(font
					(size 1.27 1.27)
				)
				(justify mirror)
			)
		)
		(property "Value" "SCD1U6D3V1KX-GP"
			(at 2.8321 -1.7399 180)
			(unlocked yes)
			(layer "B.Fab")
			(hide yes)
			(effects
				(font
					(size 1.016 1.016)
					(thickness 0.1524)
				)
				(justify mirror)
			)
		)
		(property "Device Type" "C0201H13"
			(at 2.8321 -3.2639 180)
			(unlocked yes)
			(layer "B.Fab")
			(hide yes)
			(effects
				(font
					(size 1.016 1.016)
					(thickness 0.1524)
				)
				(justify mirror)
			)
		)
		(duplicate_pad_numbers_are_jumpers no)
		(fp_rect
			(start 0.2794 0.6477)
			(end -0.2794 -0.6477)
			(stroke
				(width 0)
				(type default)
			)
			(fill no)
			(layer "B.CrtYd")
		)
		(fp_rect
			(start 0.2794 0.6477)
			(end -0.2794 -0.6477)
			(stroke
				(width 0)
				(type default)
			)
			(fill no)
			(layer "B.Fab")
		)
		(pad "1" smd custom
			(at 0 -0.2794)
			(size 0.0762 0.0762)
			(layers "B.Cu" "B.Mask" "B.Paste")
			(net "P0V9")
			(options
				(clearance outline)
				(anchor circle)
			)
			(primitives
				(gr_poly
					(pts
						(arc
							(start 0.1524 0.127)
							(mid 0.137521 0.162921)
							(end 0.1016 0.1778)
						)
						(arc
							(start -0.1016 0.1778)
							(mid -0.137521 0.162921)
							(end -0.1524 0.127)
						)
						(arc
							(start -0.1524 -0.127)
							(mid -0.137521 -0.162921)
							(end -0.1016 -0.1778)
						)
						(arc
							(start 0.1016 -0.1778)
							(mid 0.137521 -0.162921)
							(end 0.1524 -0.127)
						)
					)
					(width 0)
					(fill yes)
				)
			)
		)
		(pad "2" smd custom
			(at 0 0.2794)
			(size 0.0762 0.0762)
			(layers "B.Cu" "B.Mask" "B.Paste")
			(net "GND")
			(options
				(clearance outline)
				(anchor circle)
			)
			(primitives
				(gr_poly
					(pts
						(arc
							(start 0.1524 0.127)
							(mid 0.137521 0.162921)
							(end 0.1016 0.1778)
						)
						(arc
							(start -0.1016 0.1778)
							(mid -0.137521 0.162921)
							(end -0.1524 0.127)
						)
						(arc
							(start -0.1524 -0.127)
							(mid -0.137521 -0.162921)
							(end -0.1016 -0.1778)
						)
						(arc
							(start 0.1016 -0.1778)
							(mid 0.137521 -0.162921)
							(end 0.1524 -0.127)
						)
					)
					(width 0)
					(fill yes)
				)
			)
		)
	)
	(footprint ""
		(layer "B.Cu")
		(at 122.4788 -68.4911 -90)
		(property "Reference" "C586"
			(at 0 0 90)
			(layer "B.SilkS")
			(hide yes)
			(effects
				(font
					(size 1.27 1.27)
				)
				(justify mirror)
			)
		)
		(property "Value" "SCD1U6D3V1KX-GP"
			(at 2.8321 -1.7399 270)
			(unlocked yes)
			(layer "B.Fab")
			(hide yes)
			(effects
				(font
					(size 1.016 1.016)
					(thickness 0.1524)
				)
				(justify mirror)
			)
		)
		(property "Device Type" "C0201H13"
			(at 2.8321 -3.2639 270)
			(unlocked yes)
			(layer "B.Fab")
			(hide yes)
			(effects
				(font
					(size 1.016 1.016)
					(thickness 0.1524)
				)
				(justify mirror)
			)
		)
		(duplicate_pad_numbers_are_jumpers no)
		(fp_rect
			(start 0.2794 0.6477)
			(end -0.2794 -0.6477)
			(stroke
				(width 0)
				(type default)
			)
			(fill no)
			(layer "B.CrtYd")
		)
		(fp_rect
			(start 0.2794 0.6477)
			(end -0.2794 -0.6477)
			(stroke
				(width 0)
				(type default)
			)
			(fill no)
			(layer "B.Fab")
		)
		(pad "1" smd custom
			(at 0 -0.2794 90)
			(size 0.0762 0.0762)
			(layers "B.Cu" "B.Mask" "B.Paste")
			(net "GB_VDDA")
			(options
				(clearance outline)
				(anchor circle)
			)
			(primitives
				(gr_poly
					(pts
						(arc
							(start 0.1524 0.127)
							(mid 0.137521 0.162921)
							(end 0.1016 0.1778)
						)
						(arc
							(start -0.1016 0.1778)
							(mid -0.137521 0.162921)
							(end -0.1524 0.127)
						)
						(arc
							(start -0.1524 -0.127)
							(mid -0.137521 -0.162921)
							(end -0.1016 -0.1778)
						)
						(arc
							(start 0.1016 -0.1778)
							(mid 0.137521 -0.162921)
							(end 0.1524 -0.127)
						)
					)
					(width 0)
					(fill yes)
				)
			)
		)
		(pad "2" smd custom
			(at 0 0.2794 90)
			(size 0.0762 0.0762)
			(layers "B.Cu" "B.Mask" "B.Paste")
			(net "GND")
			(options
				(clearance outline)
				(anchor circle)
			)
			(primitives
				(gr_poly
					(pts
						(arc
							(start 0.1524 0.127)
							(mid 0.137521 0.162921)
							(end 0.1016 0.1778)
						)
						(arc
							(start -0.1016 0.1778)
							(mid -0.137521 0.162921)
							(end -0.1524 0.127)
						)
						(arc
							(start -0.1524 -0.127)
							(mid -0.137521 -0.162921)
							(end -0.1016 -0.1778)
						)
						(arc
							(start 0.1016 -0.1778)
							(mid 0.137521 -0.162921)
							(end 0.1524 -0.127)
						)
					)
					(width 0)
					(fill yes)
				)
			)
		)
	)
	(footprint ""
		(layer "B.Cu")
		(at 165.46322 -43.798236 180)
		(property "Reference" "C484"
			(at 0 0 0)
			(layer "B.SilkS")
			(hide yes)
			(effects
				(font
					(size 1.27 1.27)
				)
				(justify mirror)
			)
		)
		(property "Value" "SC1U16V2KX-7-GP"
			(at -1.7526 -1.6002 180)
			(unlocked yes)
			(layer "B.Fab")
			(hide yes)
			(effects
				(font
					(size 1.016 1.016)
					(thickness 0.1524)
				)
				(justify mirror)
			)
		)
		(property "Device Type" "C402-TO0D2H24"
			(at -1.7526 -3.1242 180)
			(unlocked yes)
			(layer "B.Fab")
			(hide yes)
			(effects
				(font
					(size 1.016 1.016)
					(thickness 0.1524)
				)
				(justify mirror)
			)
		)
		(duplicate_pad_numbers_are_jumpers no)
		(fp_rect
			(start 0.4826 0.889)
			(end -0.4826 -0.889)
			(stroke
				(width 0)
				(type default)
			)
			(fill no)
			(layer "B.CrtYd")
		)
		(fp_rect
			(start 0.4826 0.889)
			(end -0.4826 -0.889)
			(stroke
				(width 0)
				(type default)
			)
			(fill no)
			(layer "B.Fab")
		)
		(pad "1" smd custom
			(at 0 -0.4572)
			(size 0.1524 0.1524)
			(layers "B.Cu" "B.Mask" "B.Paste")
			(net "P1V8_C")
			(options
				(clearance outline)
				(anchor circle)
			)
			(primitives
				(gr_poly
					(pts
						(arc
							(start -0.254 -0.3048)
							(mid -0.325842 -0.275042)
							(end -0.3556 -0.2032)
						)
						(arc
							(start -0.3556 0.2032)
							(mid -0.325842 0.275042)
							(end -0.254 0.3048)
						)
						(arc
							(start 0.254 0.3048)
							(mid 0.325842 0.275042)
							(end 0.3556 0.2032)
						)
						(arc
							(start 0.3556 -0.2032)
							(mid 0.325842 -0.275042)
							(end 0.254 -0.3048)
						)
					)
					(width 0)
					(fill yes)
				)
			)
		)
		(pad "2" smd custom
			(at 0 0.4572)
			(size 0.1524 0.1524)
			(layers "B.Cu" "B.Mask" "B.Paste")
			(net "GND")
			(options
				(clearance outline)
				(anchor circle)
			)
			(primitives
				(gr_poly
					(pts
						(arc
							(start -0.254 -0.3048)
							(mid -0.325842 -0.275042)
							(end -0.3556 -0.2032)
						)
						(arc
							(start -0.3556 0.2032)
							(mid -0.325842 0.275042)
							(end -0.254 0.3048)
						)
						(arc
							(start 0.254 0.3048)
							(mid 0.325842 0.275042)
							(end 0.3556 0.2032)
						)
						(arc
							(start 0.3556 -0.2032)
							(mid 0.325842 -0.275042)
							(end 0.254 -0.3048)
						)
					)
					(width 0)
					(fill yes)
				)
			)
		)
	)
	(footprint ""
		(layer "B.Cu")
		(at 184.465468 -46.42993 90)
		(property "Reference" "C454"
			(at 0 0 90)
			(layer "B.SilkS")
			(hide yes)
			(effects
				(font
					(size 1.27 1.27)
				)
				(justify mirror)
			)
		)
		(property "Value" "SCD1U6D3V1KX-GP"
			(at 2.8321 -1.7399 90)
			(unlocked yes)
			(layer "B.Fab")
			(hide yes)
			(effects
				(font
					(size 1.016 1.016)
					(thickness 0.1524)
				)
				(justify mirror)
			)
		)
		(property "Device Type" "C0201H13"
			(at 2.8321 -3.2639 90)
			(unlocked yes)
			(layer "B.Fab")
			(hide yes)
			(effects
				(font
					(size 1.016 1.016)
					(thickness 0.1524)
				)
				(justify mirror)
			)
		)
		(duplicate_pad_numbers_are_jumpers no)
		(fp_rect
			(start 0.2794 0.6477)
			(end -0.2794 -0.6477)
			(stroke
				(width 0)
				(type default)
			)
			(fill no)
			(layer "B.CrtYd")
		)
		(fp_rect
			(start 0.2794 0.6477)
			(end -0.2794 -0.6477)
			(stroke
				(width 0)
				(type default)
			)
			(fill no)
			(layer "B.Fab")
		)
		(pad "1" smd custom
			(at 0 -0.2794 270)
			(size 0.0762 0.0762)
			(layers "B.Cu" "B.Mask" "B.Paste")
			(net "P1V8_C")
			(options
				(clearance outline)
				(anchor circle)
			)
			(primitives
				(gr_poly
					(pts
						(arc
							(start 0.1524 0.127)
							(mid 0.137521 0.162921)
							(end 0.1016 0.1778)
						)
						(arc
							(start -0.1016 0.1778)
							(mid -0.137521 0.162921)
							(end -0.1524 0.127)
						)
						(arc
							(start -0.1524 -0.127)
							(mid -0.137521 -0.162921)
							(end -0.1016 -0.1778)
						)
						(arc
							(start 0.1016 -0.1778)
							(mid 0.137521 -0.162921)
							(end 0.1524 -0.127)
						)
					)
					(width 0)
					(fill yes)
				)
			)
		)
		(pad "2" smd custom
			(at 0 0.2794 270)
			(size 0.0762 0.0762)
			(layers "B.Cu" "B.Mask" "B.Paste")
			(net "GND")
			(options
				(clearance outline)
				(anchor circle)
			)
			(primitives
				(gr_poly
					(pts
						(arc
							(start 0.1524 0.127)
							(mid 0.137521 0.162921)
							(end 0.1016 0.1778)
						)
						(arc
							(start -0.1016 0.1778)
							(mid -0.137521 0.162921)
							(end -0.1524 0.127)
						)
						(arc
							(start -0.1524 -0.127)
							(mid -0.137521 -0.162921)
							(end -0.1016 -0.1778)
						)
						(arc
							(start 0.1016 -0.1778)
							(mid 0.137521 -0.162921)
							(end 0.1524 -0.127)
						)
					)
					(width 0)
					(fill yes)
				)
			)
		)
	)
	(footprint ""
		(layer "B.Cu")
		(at 131.699 -89.916 180)
		(property "Reference" "R55"
			(at 0 0 0)
			(layer "B.SilkS")
			(hide yes)
			(effects
				(font
					(size 1.27 1.27)
				)
				(justify mirror)
			)
		)
		(property "Value" "4K7R2F-GP"
			(at -0.064008 -3.993896 180)
			(unlocked yes)
			(layer "B.Fab")
			(hide yes)
			(effects
				(font
					(size 1.016 1.016)
					(thickness 0.1524)
				)
				(justify mirror)
			)
		)
		(property "Device Type" "R402H16"
			(at -0.064008 -5.517896 180)
			(unlocked yes)
			(layer "B.Fab")
			(hide yes)
			(effects
				(font
					(size 1.016 1.016)
					(thickness 0.1524)
				)
				(justify mirror)
			)
		)
		(duplicate_pad_numbers_are_jumpers no)
		(fp_line
			(start 0.508 -0.9398)
			(end 0.508 0.9398)
			(stroke
				(width 0.1524)
				(type default)
			)
			(layer "B.SilkS")
		)
		(fp_line
			(start -0.508 -0.9398)
			(end 0.508 -0.9398)
			(stroke
				(width 0.1524)
				(type default)
			)
			(layer "B.SilkS")
		)
		(fp_rect
			(start 0.508 0.9398)
			(end -0.508 -0.9398)
			(stroke
				(width 0)
				(type default)
			)
			(fill no)
			(layer "B.CrtYd")
		)
		(fp_rect
			(start 0.508 0.9398)
			(end -0.508 -0.9398)
			(stroke
				(width 0)
				(type default)
			)
			(fill no)
			(layer "B.Fab")
		)
		(pad "1" smd custom
			(at 0 -0.4445)
			(size 0.1397 0.1397)
			(layers "B.Cu" "B.Mask" "B.Paste")
			(net "P1V8_E")
			(options
				(clearance outline)
				(anchor circle)
			)
			(primitives
				(gr_poly
					(pts
						(arc
							(start -0.1778 0.2794)
							(mid -0.249642 0.249642)
							(end -0.2794 0.1778)
						)
						(arc
							(start -0.2794 -0.1778)
							(mid -0.249642 -0.249642)
							(end -0.1778 -0.2794)
						)
						(arc
							(start 0.1778 -0.2794)
							(mid 0.249642 -0.249642)
							(end 0.2794 -0.1778)
						)
						(arc
							(start 0.2794 0.1778)
							(mid 0.249642 0.249642)
							(end 0.1778 0.2794)
						)
					)
					(width 0)
					(fill yes)
				)
			)
		)
		(pad "2" smd custom
			(at 0 0.4445)
			(size 0.1397 0.1397)
			(layers "B.Cu" "B.Mask" "B.Paste")
			(net "I2C_DPB_SDA3_LS")
			(options
				(clearance outline)
				(anchor circle)
			)
			(primitives
				(gr_poly
					(pts
						(arc
							(start -0.1778 0.2794)
							(mid -0.249642 0.249642)
							(end -0.2794 0.1778)
						)
						(arc
							(start -0.2794 -0.1778)
							(mid -0.249642 -0.249642)
							(end -0.1778 -0.2794)
						)
						(arc
							(start 0.1778 -0.2794)
							(mid 0.249642 -0.249642)
							(end 0.2794 -0.1778)
						)
						(arc
							(start 0.2794 0.1778)
							(mid 0.249642 0.249642)
							(end 0.1778 0.2794)
						)
					)
					(width 0)
					(fill yes)
				)
			)
		)
	)
	(footprint ""
		(layer "B.Cu")
		(at 102.743 -44.2214 180)
		(property "Reference" "C80"
			(at 0 0 0)
			(layer "B.SilkS")
			(hide yes)
			(effects
				(font
					(size 1.27 1.27)
				)
				(justify mirror)
			)
		)
		(property "Value" "SCD01U16V1KX-GP"
			(at 2.8321 -1.7399 180)
			(unlocked yes)
			(layer "B.Fab")
			(hide yes)
			(effects
				(font
					(size 1.016 1.016)
					(thickness 0.1524)
				)
				(justify mirror)
			)
		)
		(property "Device Type" "C0201H13"
			(at 2.8321 -3.2639 180)
			(unlocked yes)
			(layer "B.Fab")
			(hide yes)
			(effects
				(font
					(size 1.016 1.016)
					(thickness 0.1524)
				)
				(justify mirror)
			)
		)
		(duplicate_pad_numbers_are_jumpers no)
		(fp_rect
			(start 0.2794 0.6477)
			(end -0.2794 -0.6477)
			(stroke
				(width 0)
				(type default)
			)
			(fill no)
			(layer "B.CrtYd")
		)
		(fp_rect
			(start 0.2794 0.6477)
			(end -0.2794 -0.6477)
			(stroke
				(width 0)
				(type default)
			)
			(fill no)
			(layer "B.Fab")
		)
		(pad "1" smd custom
			(at 0 -0.2794)
			(size 0.0762 0.0762)
			(layers "B.Cu" "B.Mask" "B.Paste")
			(net "PHY_DPB_TO_SCC_20_DN")
			(options
				(clearance outline)
				(anchor circle)
			)
			(primitives
				(gr_poly
					(pts
						(arc
							(start 0.1524 0.127)
							(mid 0.137521 0.162921)
							(end 0.1016 0.1778)
						)
						(arc
							(start -0.1016 0.1778)
							(mid -0.137521 0.162921)
							(end -0.1524 0.127)
						)
						(arc
							(start -0.1524 -0.127)
							(mid -0.137521 -0.162921)
							(end -0.1016 -0.1778)
						)
						(arc
							(start 0.1016 -0.1778)
							(mid 0.137521 -0.162921)
							(end 0.1524 -0.127)
						)
					)
					(width 0)
					(fill yes)
				)
			)
		)
		(pad "2" smd custom
			(at 0 0.2794)
			(size 0.0762 0.0762)
			(layers "B.Cu" "B.Mask" "B.Paste")
			(net "PHY_DPB_TO_SCC_C_20_DN")
			(options
				(clearance outline)
				(anchor circle)
			)
			(primitives
				(gr_poly
					(pts
						(arc
							(start 0.1524 0.127)
							(mid 0.137521 0.162921)
							(end 0.1016 0.1778)
						)
						(arc
							(start -0.1016 0.1778)
							(mid -0.137521 0.162921)
							(end -0.1524 0.127)
						)
						(arc
							(start -0.1524 -0.127)
							(mid -0.137521 -0.162921)
							(end -0.1016 -0.1778)
						)
						(arc
							(start 0.1016 -0.1778)
							(mid 0.137521 -0.162921)
							(end 0.1524 -0.127)
						)
					)
					(width 0)
					(fill yes)
				)
			)
		)
	)
	(footprint ""
		(layer "B.Cu")
		(at 198.502778 -31.900622)
		(property "Reference" "C364"
			(at 0 0 0)
			(layer "B.SilkS")
			(hide yes)
			(effects
				(font
					(size 1.27 1.27)
				)
				(justify mirror)
			)
		)
		(property "Value" "SC10U6D3V5KX-4GP"
			(at 0.0762 -6.1214 0)
			(unlocked yes)
			(layer "B.Fab")
			(hide yes)
			(effects
				(font
					(size 1.016 1.016)
					(thickness 0.1524)
				)
				(justify mirror)
			)
		)
		(property "Device Type" "C805H58"
			(at 0.0762 -8.1534 0)
			(unlocked yes)
			(layer "B.Fab")
			(hide yes)
			(effects
				(font
					(size 1.016 1.016)
					(thickness 0.1524)
				)
				(justify mirror)
			)
		)
		(duplicate_pad_numbers_are_jumpers no)
		(fp_line
			(start -0.635 0)
			(end 0.635 0)
			(stroke
				(width 0.508)
				(type default)
			)
			(layer "B.SilkS")
		)
		(fp_rect
			(start 0.9652 1.778)
			(end -0.9652 -1.778)
			(stroke
				(width 0)
				(type default)
			)
			(fill no)
			(layer "B.CrtYd")
		)
		(fp_poly
			(pts
				(xy 0.9652 -1.778) (xy -0.9652 -1.778) (xy -0.9652 1.778) (xy 0.9652 1.778)
			)
			(stroke
				(width 0)
				(type default)
			)
			(fill no)
			(layer "B.Fab")
		)
		(pad "1" smd rect
			(at 0 -0.9652 180)
			(size 1.397 1.143)
			(layers "B.Cu" "B.Mask" "B.Paste")
			(net "PLL_VDD")
		)
		(pad "2" smd rect
			(at 0 0.9652 180)
			(size 1.397 1.143)
			(layers "B.Cu" "B.Mask" "B.Paste")
			(net "GND")
		)
	)
)
